(kicad_pcb
	(version 20260206)
	(generator "pcbnew")
	(generator_version "10.0")
	(general
		(thickness 1.6)
		(legacy_teardrops no)
	)
	(paper "A4")
	(title_block
		(title "baseboard — 13948-1b.1110WZS1818.brd")
		(comment 1 "Honey Badger (Wiwynn) / footprints 464-469 of 2523")
	)
	(layers
		(0 "F.Cu" signal "TOP")
		(4 "In1.Cu" signal "L2GND")
		(6 "In2.Cu" signal "L3")
		(8 "In3.Cu" signal "L4VCC")
		(10 "In4.Cu" signal "L5VCC")
		(12 "In5.Cu" signal "L6")
		(14 "In6.Cu" signal "L7GND")
		(2 "B.Cu" signal "BOTTOM")
		(9 "F.Adhes" user "F.Adhesive")
		(11 "B.Adhes" user "B.Adhesive")
		(13 "F.Paste" user "Package Geometry/Pastemask Top")
		(15 "B.Paste" user "Package Geometry/Pastemask Bottom")
		(5 "F.SilkS" user "Ref Des/Silkscreen Top")
		(7 "B.SilkS" user "Ref Des/Silkscreen Bottom")
		(1 "F.Mask" user "Board Geometry/Soldermask Top")
		(3 "B.Mask" user "Board Geometry/Soldermask Bottom")
		(17 "Dwgs.User" user "User.Drawings")
		(19 "Cmts.User" user "User.Comments")
		(21 "Eco1.User" user "User.Eco1")
		(23 "Eco2.User" user "User.Eco2")
		(25 "Edge.Cuts" user "Board Geometry/Outline")
		(27 "Margin" user)
		(31 "F.CrtYd" user "Package Geometry/Place Bound Top")
		(29 "B.CrtYd" user "Package Geometry/Place Bound Bottom")
		(35 "F.Fab" user "Ref Des/Assembly Top")
		(33 "B.Fab" user "Ref Des/Assembly Bottom")
	)
	(footprint ""
		(layer "F.Cu")
		(at 56.134 -180.086 180)
		(property "Reference" "SR812"
			(at 0 0 180)
			(layer "F.SilkS")
			(hide yes)
			(effects
				(font
					(size 1.27 1.27)
				)
			)
		)
		(property "Value" "4K75R2F-1-GP"
			(at 0.064008 -3.993896 180)
			(unlocked yes)
			(layer "F.Fab")
			(hide yes)
			(effects
				(font
					(size 1.016 1.016)
					(thickness 0.1524)
				)
			)
		)
		(property "Device Type" "R402H16"
			(at 0.064008 -5.517896 180)
			(unlocked yes)
			(layer "F.Fab")
			(hide yes)
			(effects
				(font
					(size 1.016 1.016)
					(thickness 0.1524)
				)
			)
		)
		(duplicate_pad_numbers_are_jumpers no)
		(fp_line
			(start 0.508 -0.9398)
			(end -0.508 -0.9398)
			(stroke
				(width 0.1524)
				(type default)
			)
			(layer "F.SilkS")
		)
		(fp_line
			(start -0.508 -0.9398)
			(end -0.508 0.9398)
			(stroke
				(width 0.1524)
				(type default)
			)
			(layer "F.SilkS")
		)
		(fp_rect
			(start -0.508 0.9398)
			(end 0.508 -0.9398)
			(stroke
				(width 0)
				(type default)
			)
			(fill no)
			(layer "F.CrtYd")
		)
		(fp_rect
			(start -0.508 0.9398)
			(end 0.508 -0.9398)
			(stroke
				(width 0)
				(type default)
			)
			(fill no)
			(layer "F.Fab")
		)
		(pad "1" smd custom
			(at 0 -0.4445 180)
			(size 0.1397 0.1397)
			(layers "F.Cu" "F.Mask" "F.Paste")
			(net "P1V8_E")
			(options
				(clearance outline)
				(anchor circle)
			)
			(primitives
				(gr_poly
					(pts
						(arc
							(start -0.1778 -0.2794)
							(mid -0.249642 -0.249642)
							(end -0.2794 -0.1778)
						)
						(arc
							(start -0.2794 0.1778)
							(mid -0.249642 0.249642)
							(end -0.1778 0.2794)
						)
						(arc
							(start 0.1778 0.2794)
							(mid 0.249642 0.249642)
							(end 0.2794 0.1778)
						)
						(arc
							(start 0.2794 -0.1778)
							(mid 0.249642 -0.249642)
							(end 0.1778 -0.2794)
						)
					)
					(width 0)
					(fill yes)
				)
			)
		)
		(pad "2" smd custom
			(at 0 0.4445 180)
			(size 0.1397 0.1397)
			(layers "F.Cu" "F.Mask" "F.Paste")
			(net "ICE_TCK")
			(options
				(clearance outline)
				(anchor circle)
			)
			(primitives
				(gr_poly
					(pts
						(arc
							(start -0.1778 -0.2794)
							(mid -0.249642 -0.249642)
							(end -0.2794 -0.1778)
						)
						(arc
							(start -0.2794 0.1778)
							(mid -0.249642 0.249642)
							(end -0.1778 0.2794)
						)
						(arc
							(start 0.1778 0.2794)
							(mid 0.249642 0.249642)
							(end 0.2794 0.1778)
						)
						(arc
							(start 0.2794 -0.1778)
							(mid 0.249642 -0.249642)
							(end 0.1778 -0.2794)
						)
					)
					(width 0)
					(fill yes)
				)
			)
		)
	)
	(footprint ""
		(layer "F.Cu")
		(at 257.483864 -223.511872 90)
		(property "Reference" "PC100"
			(at 0 0 90)
			(layer "F.SilkS")
			(hide yes)
			(effects
				(font
					(size 1.27 1.27)
				)
			)
		)
		(property "Value" "SC470P50V2KX-3GP"
			(at 1.1811 -2.7051 90)
			(unlocked yes)
			(layer "F.Fab")
			(hide yes)
			(effects
				(font
					(size 1.016 1.016)
					(thickness 0.1524)
				)
			)
		)
		(property "Device Type" "C402H22"
			(at 1.1811 -4.2291 90)
			(unlocked yes)
			(layer "F.Fab")
			(hide yes)
			(effects
				(font
					(size 1.016 1.016)
					(thickness 0.1524)
				)
			)
		)
		(duplicate_pad_numbers_are_jumpers no)
		(fp_rect
			(start -0.4318 0.9525)
			(end 0.4318 -0.9525)
			(stroke
				(width 0)
				(type default)
			)
			(fill no)
			(layer "F.CrtYd")
		)
		(fp_rect
			(start -0.4318 0.9525)
			(end 0.4318 -0.9525)
			(stroke
				(width 0)
				(type default)
			)
			(fill no)
			(layer "F.Fab")
		)
		(pad "1" smd custom
			(at 0 -0.4445 90)
			(size 0.1524 0.1524)
			(layers "F.Cu" "F.Mask" "F.Paste")
			(net "GND")
			(options
				(clearance outline)
				(anchor circle)
			)
			(primitives
				(gr_poly
					(pts
						(arc
							(start 0.3048 -0.2032)
							(mid 0.275042 -0.275042)
							(end 0.2032 -0.3048)
						)
						(arc
							(start -0.2032 -0.3048)
							(mid -0.275042 -0.275042)
							(end -0.3048 -0.2032)
						)
						(arc
							(start -0.3048 0.2032)
							(mid -0.275042 0.275042)
							(end -0.2032 0.3048)
						)
						(arc
							(start 0.2032 0.3048)
							(mid 0.275042 0.275042)
							(end 0.3048 0.2032)
						)
					)
					(width 0)
					(fill yes)
				)
			)
		)
		(pad "2" smd custom
			(at 0 0.4445 90)
			(size 0.1524 0.1524)
			(layers "F.Cu" "F.Mask" "F.Paste")
			(net "TPS74801_1V26_STBY_SS")
			(options
				(clearance outline)
				(anchor circle)
			)
			(primitives
				(gr_poly
					(pts
						(arc
							(start 0.3048 -0.2032)
							(mid 0.275042 -0.275042)
							(end 0.2032 -0.3048)
						)
						(arc
							(start -0.2032 -0.3048)
							(mid -0.275042 -0.275042)
							(end -0.3048 -0.2032)
						)
						(arc
							(start -0.3048 0.2032)
							(mid -0.275042 0.275042)
							(end -0.2032 0.3048)
						)
						(arc
							(start 0.2032 0.3048)
							(mid 0.275042 0.275042)
							(end 0.3048 0.2032)
						)
					)
					(width 0)
					(fill yes)
				)
			)
		)
	)
	(footprint ""
		(layer "F.Cu")
		(at 117.475 -32.131)
		(property "Reference" "STP141"
			(at 0 0 0)
			(layer "F.SilkS")
			(hide yes)
			(effects
				(font
					(size 1.27 1.27)
				)
			)
		)
		(property "Value" "TPAD28"
			(at 0.0127 -1.8034 0)
			(unlocked yes)
			(layer "F.Fab")
			(hide yes)
			(effects
				(font
					(size 1.016 1.016)
					(thickness 0.1524)
				)
			)
		)
		(property "Device Type" "TPAD28"
			(at 0.0127 -3.3274 0)
			(unlocked yes)
			(layer "F.Fab")
			(hide yes)
			(effects
				(font
					(size 1.016 1.016)
					(thickness 0.1524)
				)
			)
		)
		(duplicate_pad_numbers_are_jumpers no)
		(fp_poly
			(pts
				(arc
					(start 0.3556 0)
					(mid -0.3556 0)
					(end 0.3556 0)
				)
			)
			(stroke
				(width 0)
				(type default)
			)
			(fill no)
			(layer "F.CrtYd")
		)
		(fp_poly
			(pts
				(arc
					(start 0.6096 0)
					(mid -0.6096 0)
					(end 0.6096 0)
				)
			)
			(stroke
				(width 0)
				(type default)
			)
			(fill no)
			(layer "F.Fab")
		)
		(pad "1" smd circle
			(at 0 0)
			(size 0.7112 0.7112)
			(layers "F.Cu" "F.Mask" "F.Paste")
			(net "IOC_GPIO_22")
		)
	)
	(footprint ""
		(layer "F.Cu")
		(at 16.071088 -202.185016)
		(property "Reference" "SR578"
			(at 0 0 0)
			(layer "F.SilkS")
			(hide yes)
			(effects
				(font
					(size 1.27 1.27)
				)
			)
		)
		(property "Value" "4K7R2F-GP"
			(at 0.064008 -3.993896 0)
			(unlocked yes)
			(layer "F.Fab")
			(hide yes)
			(effects
				(font
					(size 1.016 1.016)
					(thickness 0.1524)
				)
			)
		)
		(property "Device Type" "R402H16"
			(at 0.064008 -5.517896 0)
			(unlocked yes)
			(layer "F.Fab")
			(hide yes)
			(effects
				(font
					(size 1.016 1.016)
					(thickness 0.1524)
				)
			)
		)
		(duplicate_pad_numbers_are_jumpers no)
		(fp_line
			(start -0.508 -0.9398)
			(end -0.508 0.9398)
			(stroke
				(width 0.1524)
				(type default)
			)
			(layer "F.SilkS")
		)
		(fp_line
			(start 0.508 -0.9398)
			(end -0.508 -0.9398)
			(stroke
				(width 0.1524)
				(type default)
			)
			(layer "F.SilkS")
		)
		(fp_rect
			(start -0.508 0.9398)
			(end 0.508 -0.9398)
			(stroke
				(width 0)
				(type default)
			)
			(fill no)
			(layer "F.CrtYd")
		)
		(fp_rect
			(start -0.508 0.9398)
			(end 0.508 -0.9398)
			(stroke
				(width 0)
				(type default)
			)
			(fill no)
			(layer "F.Fab")
		)
		(pad "1" smd custom
			(at 0 -0.4445)
			(size 0.1397 0.1397)
			(layers "F.Cu" "F.Mask" "F.Paste")
			(net "BMC_I2C_SCL_10")
			(options
				(clearance outline)
				(anchor circle)
			)
			(primitives
				(gr_poly
					(pts
						(arc
							(start -0.1778 -0.2794)
							(mid -0.249642 -0.249642)
							(end -0.2794 -0.1778)
						)
						(arc
							(start -0.2794 0.1778)
							(mid -0.249642 0.249642)
							(end -0.1778 0.2794)
						)
						(arc
							(start 0.1778 0.2794)
							(mid 0.249642 0.249642)
							(end 0.2794 0.1778)
						)
						(arc
							(start 0.2794 -0.1778)
							(mid 0.249642 -0.249642)
							(end 0.1778 -0.2794)
						)
					)
					(width 0)
					(fill yes)
				)
			)
		)
		(pad "2" smd custom
			(at 0 0.4445)
			(size 0.1397 0.1397)
			(layers "F.Cu" "F.Mask" "F.Paste")
			(net "P3V3_STBY")
			(options
				(clearance outline)
				(anchor circle)
			)
			(primitives
				(gr_poly
					(pts
						(arc
							(start -0.1778 -0.2794)
							(mid -0.249642 -0.249642)
							(end -0.2794 -0.1778)
						)
						(arc
							(start -0.2794 0.1778)
							(mid -0.249642 0.249642)
							(end -0.1778 0.2794)
						)
						(arc
							(start 0.1778 0.2794)
							(mid 0.249642 0.249642)
							(end 0.2794 0.1778)
						)
						(arc
							(start 0.2794 -0.1778)
							(mid 0.249642 -0.249642)
							(end 0.1778 -0.2794)
						)
					)
					(width 0)
					(fill yes)
				)
			)
		)
	)
	(footprint ""
		(layer "F.Cu")
		(at 160.02 -146.05 -90)
		(property "Reference" "SC1287"
			(at 0 0 270)
			(layer "F.SilkS")
			(hide yes)
			(effects
				(font
					(size 1.27 1.27)
				)
			)
		)
		(property "Value" "SCD1U16V2KX-3GP"
			(at 1.1811 -2.7051 270)
			(unlocked yes)
			(layer "F.Fab")
			(hide yes)
			(effects
				(font
					(size 1.016 1.016)
					(thickness 0.1524)
				)
			)
		)
		(property "Device Type" "C402H22"
			(at 1.1811 -4.2291 270)
			(unlocked yes)
			(layer "F.Fab")
			(hide yes)
			(effects
				(font
					(size 1.016 1.016)
					(thickness 0.1524)
				)
			)
		)
		(duplicate_pad_numbers_are_jumpers no)
		(fp_rect
			(start -0.4318 0.9525)
			(end 0.4318 -0.9525)
			(stroke
				(width 0)
				(type default)
			)
			(fill no)
			(layer "F.CrtYd")
		)
		(fp_rect
			(start -0.4318 0.9525)
			(end 0.4318 -0.9525)
			(stroke
				(width 0)
				(type default)
			)
			(fill no)
			(layer "F.Fab")
		)
		(pad "1" smd custom
			(at 0 -0.4445 270)
			(size 0.1524 0.1524)
			(layers "F.Cu" "F.Mask" "F.Paste")
			(net "IOC_I2C_VREF")
			(options
				(clearance outline)
				(anchor circle)
			)
			(primitives
				(gr_poly
					(pts
						(arc
							(start 0.3048 -0.2032)
							(mid 0.275042 -0.275042)
							(end 0.2032 -0.3048)
						)
						(arc
							(start -0.2032 -0.3048)
							(mid -0.275042 -0.275042)
							(end -0.3048 -0.2032)
						)
						(arc
							(start -0.3048 0.2032)
							(mid -0.275042 0.275042)
							(end -0.2032 0.3048)
						)
						(arc
							(start 0.2032 0.3048)
							(mid 0.275042 0.275042)
							(end 0.3048 0.2032)
						)
					)
					(width 0)
					(fill yes)
				)
			)
		)
		(pad "2" smd custom
			(at 0 0.4445 270)
			(size 0.1524 0.1524)
			(layers "F.Cu" "F.Mask" "F.Paste")
			(net "GND")
			(options
				(clearance outline)
				(anchor circle)
			)
			(primitives
				(gr_poly
					(pts
						(arc
							(start 0.3048 -0.2032)
							(mid 0.275042 -0.275042)
							(end 0.2032 -0.3048)
						)
						(arc
							(start -0.2032 -0.3048)
							(mid -0.275042 -0.275042)
							(end -0.3048 -0.2032)
						)
						(arc
							(start -0.3048 0.2032)
							(mid -0.275042 0.275042)
							(end -0.2032 0.3048)
						)
						(arc
							(start 0.2032 0.3048)
							(mid 0.275042 0.275042)
							(end 0.3048 0.2032)
						)
					)
					(width 0)
					(fill yes)
				)
			)
		)
	)
	(footprint ""
		(layer "F.Cu")
		(at 296.545 -161.544 180)
		(property "Reference" "R284"
			(at 0 0 180)
			(layer "F.SilkS")
			(hide yes)
			(effects
				(font
					(size 1.27 1.27)
				)
			)
		)
		(property "Value" "0R2J-2-GP"
			(at 0.064008 -3.993896 180)
			(unlocked yes)
			(layer "F.Fab")
			(hide yes)
			(effects
				(font
					(size 1.016 1.016)
					(thickness 0.1524)
				)
			)
		)
		(property "Device Type" "R402H16"
			(at 0.064008 -5.517896 180)
			(unlocked yes)
			(layer "F.Fab")
			(hide yes)
			(effects
				(font
					(size 1.016 1.016)
					(thickness 0.1524)
				)
			)
		)
		(duplicate_pad_numbers_are_jumpers no)
		(fp_line
			(start 0.508 -0.9398)
			(end -0.508 -0.9398)
			(stroke
				(width 0.1524)
				(type default)
			)
			(layer "F.SilkS")
		)
		(fp_line
			(start -0.508 -0.9398)
			(end -0.508 0.9398)
			(stroke
				(width 0.1524)
				(type default)
			)
			(layer "F.SilkS")
		)
		(fp_rect
			(start -0.508 0.9398)
			(end 0.508 -0.9398)
			(stroke
				(width 0)
				(type default)
			)
			(fill no)
			(layer "F.CrtYd")
		)
		(fp_rect
			(start -0.508 0.9398)
			(end 0.508 -0.9398)
			(stroke
				(width 0)
				(type default)
			)
			(fill no)
			(layer "F.Fab")
		)
		(pad "1" smd custom
			(at 0 -0.4445 180)
			(size 0.1397 0.1397)
			(layers "F.Cu" "F.Mask" "F.Paste")
			(net "RMII_PHY_BMC_RXD1")
			(options
				(clearance outline)
				(anchor circle)
			)
			(primitives
				(gr_poly
					(pts
						(arc
							(start -0.1778 -0.2794)
							(mid -0.249642 -0.249642)
							(end -0.2794 -0.1778)
						)
						(arc
							(start -0.2794 0.1778)
							(mid -0.249642 0.249642)
							(end -0.1778 0.2794)
						)
						(arc
							(start 0.1778 0.2794)
							(mid 0.249642 0.249642)
							(end 0.2794 0.1778)
						)
						(arc
							(start 0.2794 -0.1778)
							(mid 0.249642 -0.249642)
							(end 0.1778 -0.2794)
						)
					)
					(width 0)
					(fill yes)
				)
			)
		)
		(pad "2" smd custom
			(at 0 0.4445 180)
			(size 0.1397 0.1397)
			(layers "F.Cu" "F.Mask" "F.Paste")
			(net "RMII0_PHY_BMC_C_RXD1")
			(options
				(clearance outline)
				(anchor circle)
			)
			(primitives
				(gr_poly
					(pts
						(arc
							(start -0.1778 -0.2794)
							(mid -0.249642 -0.249642)
							(end -0.2794 -0.1778)
						)
						(arc
							(start -0.2794 0.1778)
							(mid -0.249642 0.249642)
							(end -0.1778 0.2794)
						)
						(arc
							(start 0.1778 0.2794)
							(mid 0.249642 0.249642)
							(end 0.2794 0.1778)
						)
						(arc
							(start 0.2794 -0.1778)
							(mid 0.249642 -0.249642)
							(end 0.1778 -0.2794)
						)
					)
					(width 0)
					(fill yes)
				)
			)
		)
	)
)
